(kicad_pcb
	(version 20241229)
	(generator "pcbnew")
	(generator_version "9.0")
	(general
		(thickness 1.62)
		(legacy_teardrops no)
	)
	(paper "A3")
	(title_block
		(title "COM Express 7 Baseboard")
		(date "2025-02-04")
		(rev "1.1.2")
		(company "Antmicro Ltd")
		(comment 1 "www.antmicro.com")
		(comment 9 "footprints 565-570 of 802")
	)
	(layers
		(0 "F.Cu" signal)
		(4 "In1.Cu" signal)
		(6 "In2.Cu" signal)
		(8 "In3.Cu" signal)
		(10 "In4.Cu" signal)
		(12 "In5.Cu" signal)
		(14 "In6.Cu" signal)
		(2 "B.Cu" signal)
		(9 "F.Adhes" user "F.Adhesive")
		(11 "B.Adhes" user "B.Adhesive")
		(13 "F.Paste" user)
		(15 "B.Paste" user)
		(5 "F.SilkS" user "F.Silkscreen")
		(7 "B.SilkS" user "B.Silkscreen")
		(1 "F.Mask" user)
		(3 "B.Mask" user)
		(17 "Dwgs.User" user "User.Drawings")
		(19 "Cmts.User" user "User.Comments")
		(21 "Eco1.User" user "User.Eco1")
		(23 "Eco2.User" user "User.Eco2")
		(25 "Edge.Cuts" user)
		(27 "Margin" user)
		(31 "F.CrtYd" user "F.Courtyard")
		(29 "B.CrtYd" user "B.Courtyard")
		(35 "F.Fab" user)
		(33 "B.Fab" user)
	)
	(footprint "antmicro-footprints:TP_SMD_0.75mm"
		(layer "B.Cu")
		(at 123.4 145.71 180)
		(property "Reference" "TP49"
			(at -3.15 -0.47 0)
			(layer "B.SilkS")
			(effects
				(font
					(size 0.7 0.7)
					(thickness 0.15)
				)
				(justify left bottom mirror)
			)
		)
		(property "Value" "TP_0.75mm_SMD"
			(at 0 -1.2 0)
			(layer "B.Fab")
			(effects
				(font
					(size 0.7 0.7)
					(thickness 0.15)
				)
				(justify left bottom mirror)
			)
		)
		(property "Author" "Antmicro"
			(at 246.8 291.42 0)
			(layer "B.Fab")
			(hide yes)
			(effects
				(font
					(size 1 1)
					(thickness 0.15)
				)
				(justify mirror)
			)
		)
		(property "License" "Apache-2.0"
			(at 246.8 291.42 0)
			(layer "B.Fab")
			(hide yes)
			(effects
				(font
					(size 1 1)
					(thickness 0.15)
				)
				(justify mirror)
			)
		)
		(property "MPN" ""
			(at 246.8 291.42 0)
			(layer "B.Fab")
			(hide yes)
			(effects
				(font
					(size 1 1)
					(thickness 0.15)
				)
				(justify mirror)
			)
		)
		(property "Manufacturer" ""
			(at 246.8 291.42 0)
			(layer "B.Fab")
			(hide yes)
			(effects
				(font
					(size 1 1)
					(thickness 0.15)
				)
				(justify mirror)
			)
		)
		(property "Public" "False"
			(at 246.8 291.42 0)
			(layer "B.Fab")
			(hide yes)
			(effects
				(font
					(size 1 1)
					(thickness 0.15)
				)
				(justify mirror)
			)
		)
		(sheetname "PCIe redriver")
		(sheetfile "pcie_redriver.kicad_sch")
		(attr exclude_from_pos_files exclude_from_bom)
		(fp_circle
			(center 0 0)
			(end 0.475 0)
			(stroke
				(width 0.05)
				(type default)
			)
			(fill no)
			(layer "B.CrtYd")
		)
		(pad "1" smd circle
			(at 0 0 180)
			(size 0.75 0.75)
			(layers "B.Cu" "B.Mask")
			(net 712 "Net-(U39-SDA)")
			(pinfunction "1")
			(pintype "passive")
			(teardrops
				(best_length_ratio 0.4)
				(max_length 1)
				(best_width_ratio 0.9)
				(max_width 2)
				(curved_edges yes)
				(filter_ratio 0.9)
				(enabled yes)
				(allow_two_segments yes)
				(prefer_zone_connections yes)
			)
		)
	)
	(footprint "antmicro-footprints:R_0402_1005Metric"
		(layer "B.Cu")
		(at 157.9 138.36 180)
		(descr "Resistor SMD 0402")
		(tags "resistor SMD 0402")
		(property "Reference" "R253"
			(at -3.7 -0.45 0)
			(layer "B.SilkS")
			(effects
				(font
					(size 0.7 0.7)
					(thickness 0.15)
				)
				(justify left bottom mirror)
			)
		)
		(property "Value" "R_10k_0402"
			(at -1.011843 -1.772047 0)
			(layer "B.Fab")
			(effects
				(font
					(size 0.7 0.7)
					(thickness 0.15)
				)
				(justify left bottom mirror)
			)
		)
		(property "Datasheet" "https://www.bourns.com/docs/product-datasheets/cr.pdf"
			(at 0 0 180)
			(layer "F.Fab")
			(hide yes)
			(effects
				(font
					(size 1.27 1.27)
					(thickness 0.15)
				)
			)
		)
		(property "Author" "Antmicro"
			(at 315.8 276.72 0)
			(layer "B.Fab")
			(hide yes)
			(effects
				(font
					(size 1 1)
					(thickness 0.15)
				)
				(justify mirror)
			)
		)
		(property "License" "Apache-2.0"
			(at 315.8 276.72 0)
			(layer "B.Fab")
			(hide yes)
			(effects
				(font
					(size 1 1)
					(thickness 0.15)
				)
				(justify mirror)
			)
		)
		(property "MPN" "CR0402-FX-1002GLF"
			(at 315.8 276.72 0)
			(layer "B.Fab")
			(hide yes)
			(effects
				(font
					(size 1 1)
					(thickness 0.15)
				)
				(justify mirror)
			)
		)
		(property "Manufacturer" "Bourns"
			(at 315.8 276.72 0)
			(layer "B.Fab")
			(hide yes)
			(effects
				(font
					(size 1 1)
					(thickness 0.15)
				)
				(justify mirror)
			)
		)
		(property "Public" "False"
			(at 315.8 276.72 0)
			(layer "B.Fab")
			(hide yes)
			(effects
				(font
					(size 1 1)
					(thickness 0.15)
				)
				(justify mirror)
			)
		)
		(property "Tolerance" "1%"
			(at 315.8 276.72 0)
			(layer "B.Fab")
			(hide yes)
			(effects
				(font
					(size 1 1)
					(thickness 0.15)
				)
				(justify mirror)
			)
		)
		(property "Val" "10k"
			(at 315.8 276.72 0)
			(layer "B.Fab")
			(hide yes)
			(effects
				(font
					(size 1 1)
					(thickness 0.15)
				)
				(justify mirror)
			)
		)
		(sheetname "KR to SFI #1")
		(sheetfile "kr_sfi.kicad_sch")
		(attr smd)
		(fp_rect
			(start -0.925 0.47)
			(end 0.925 -0.47)
			(stroke
				(width 0.05)
				(type default)
			)
			(fill no)
			(layer "B.CrtYd")
		)
		(fp_rect
			(start -0.5 0.25)
			(end 0.5 -0.25)
			(stroke
				(width 0.15)
				(type solid)
			)
			(fill no)
			(layer "B.Fab")
		)
		(pad "1" smd roundrect
			(at -0.48 0 180)
			(size 0.59 0.64)
			(layers "B.Cu" "B.Mask" "B.Paste")
			(roundrect_rratio 0.25)
			(net 1 "GND")
			(pintype "passive")
			(teardrops
				(best_length_ratio 0.2)
				(max_length 1)
				(best_width_ratio 0.9)
				(max_width 2)
				(curved_edges yes)
				(filter_ratio 0.9)
				(enabled yes)
				(allow_two_segments yes)
				(prefer_zone_connections yes)
			)
		)
		(pad "2" smd roundrect
			(at 0.48 0 180)
			(size 0.59 0.64)
			(layers "B.Cu" "B.Mask" "B.Paste")
			(roundrect_rratio 0.25)
			(net 652 "/2xSFP+/KR to SFI #1/PRBSEN")
			(pintype "passive")
			(teardrops
				(best_length_ratio 0.2)
				(max_length 1)
				(best_width_ratio 0.9)
				(max_width 2)
				(curved_edges yes)
				(filter_ratio 0.9)
				(enabled yes)
				(allow_two_segments yes)
				(prefer_zone_connections yes)
			)
		)
	)
	(footprint "antmicro-footprints:TP_SMD_0.75mm"
		(layer "B.Cu")
		(at 180.8 160.15 180)
		(property "Reference" "TP20"
			(at -3.45 -0.6 0)
			(layer "B.SilkS")
			(effects
				(font
					(size 0.7 0.7)
					(thickness 0.15)
				)
				(justify left bottom mirror)
			)
		)
		(property "Value" "TP_0.75mm_SMD"
			(at 3.225 -53.865 0)
			(layer "B.Fab")
			(hide yes)
			(effects
				(font
					(size 0.7 0.7)
					(thickness 0.15)
				)
				(justify left bottom mirror)
			)
		)
		(property "Author" "Antmicro"
			(at 444.9 323.42 0)
			(layer "B.Fab")
			(hide yes)
			(effects
				(font
					(size 1 1)
					(thickness 0.15)
				)
				(justify mirror)
			)
		)
		(property "License" "Apache-2.0"
			(at 444.9 323.42 0)
			(layer "B.Fab")
			(hide yes)
			(effects
				(font
					(size 1 1)
					(thickness 0.15)
				)
				(justify mirror)
			)
		)
		(property "MPN" ""
			(at 444.9 323.42 0)
			(layer "B.Fab")
			(hide yes)
			(effects
				(font
					(size 1 1)
					(thickness 0.15)
				)
				(justify mirror)
			)
		)
		(property "Manufacturer" ""
			(at 444.9 323.42 0)
			(layer "B.Fab")
			(hide yes)
			(effects
				(font
					(size 1 1)
					(thickness 0.15)
				)
				(justify mirror)
			)
		)
		(property "Public" "False"
			(at 444.9 323.42 0)
			(layer "B.Fab")
			(hide yes)
			(effects
				(font
					(size 1 1)
					(thickness 0.15)
				)
				(justify mirror)
			)
		)
		(sheetname "Com Express 7 Interfaces")
		(sheetfile "com_express_7_interfaces.kicad_sch")
		(attr exclude_from_pos_files exclude_from_bom)
		(fp_circle
			(center 0 0)
			(end 0.475 0)
			(stroke
				(width 0.05)
				(type default)
			)
			(fill no)
			(layer "B.CrtYd")
		)
		(pad "1" smd circle
			(at 0 0 180)
			(size 0.75 0.75)
			(layers "B.Cu" "B.Mask")
			(net 409 "Net-(J12K-10G_SDP2)")
			(pinfunction "1")
			(pintype "passive")
			(teardrops
				(best_length_ratio 0.4)
				(max_length 1)
				(best_width_ratio 0.9)
				(max_width 2)
				(curved_edges yes)
				(filter_ratio 0.9)
				(enabled yes)
				(allow_two_segments yes)
				(prefer_zone_connections yes)
			)
		)
	)
	(footprint "antmicro-footprints:TP_SMD_0.75mm"
		(layer "B.Cu")
		(at 221.18 128.2)
		(property "Reference" "TP47"
			(at 0.37 0.46 0)
			(layer "B.SilkS")
			(effects
				(font
					(size 0.7 0.7)
					(thickness 0.15)
				)
				(justify right bottom mirror)
			)
		)
		(property "Value" "TP_0.75mm_SMD"
			(at 0 -1.2 0)
			(layer "B.Fab")
			(effects
				(font
					(size 0.7 0.7)
					(thickness 0.15)
				)
				(justify right bottom mirror)
			)
		)
		(property "Author" "Antmicro"
			(at 0 0 0)
			(layer "B.Fab")
			(hide yes)
			(effects
				(font
					(size 1 1)
					(thickness 0.15)
				)
				(justify mirror)
			)
		)
		(property "License" "Apache-2.0"
			(at 0 0 0)
			(layer "B.Fab")
			(hide yes)
			(effects
				(font
					(size 1 1)
					(thickness 0.15)
				)
				(justify mirror)
			)
		)
		(property "MPN" ""
			(at 0 0 0)
			(layer "B.Fab")
			(hide yes)
			(effects
				(font
					(size 1 1)
					(thickness 0.15)
				)
				(justify mirror)
			)
		)
		(property "Manufacturer" ""
			(at 0 0 0)
			(layer "B.Fab")
			(hide yes)
			(effects
				(font
					(size 1 1)
					(thickness 0.15)
				)
				(justify mirror)
			)
		)
		(property "Public" "False"
			(at 0 0 0)
			(layer "B.Fab")
			(hide yes)
			(effects
				(font
					(size 1 1)
					(thickness 0.15)
				)
				(justify mirror)
			)
		)
		(sheetname "PCIe misc")
		(sheetfile "pcie_misc.kicad_sch")
		(attr exclude_from_pos_files exclude_from_bom)
		(fp_circle
			(center 0 0)
			(end 0.475 0)
			(stroke
				(width 0.05)
				(type default)
			)
			(fill no)
			(layer "B.CrtYd")
		)
		(pad "1" smd circle
			(at 0 0)
			(size 0.75 0.75)
			(layers "B.Cu" "B.Mask")
			(net 621 "/PCIe misc/DIF5+")
			(pinfunction "1")
			(pintype "passive")
			(teardrops
				(best_length_ratio 0.4)
				(max_length 1)
				(best_width_ratio 0.9)
				(max_width 2)
				(curved_edges yes)
				(filter_ratio 0.9)
				(enabled yes)
				(allow_two_segments yes)
				(prefer_zone_connections yes)
			)
		)
	)
	(footprint "antmicro-footprints:C_0402_1005Metric"
		(layer "B.Cu")
		(at 133.29 139.36 -90)
		(descr "Capacitor SMD 0402")
		(tags "capacitor SMD 0402")
		(property "Reference" "C190"
			(at -0.95 -1.41 90)
			(layer "B.SilkS")
			(effects
				(font
					(size 0.7 0.7)
					(thickness 0.15)
				)
				(justify left bottom mirror)
			)
		)
		(property "Value" "C_100n_0402"
			(at -1.022927 -2.155213 90)
			(layer "B.Fab")
			(effects
				(font
					(size 0.7 0.7)
					(thickness 0.15)
				)
				(justify left bottom mirror)
			)
		)
		(property "Datasheet" "https://www.murata.com/products/productdetail?partno=GRM155R61H104KE14%23"
			(at 0 0 270)
			(layer "F.Fab")
			(hide yes)
			(effects
				(font
					(size 1.27 1.27)
					(thickness 0.15)
				)
			)
		)
		(property "Author" "Antmicro"
			(at -6.07 272.65 0)
			(layer "B.Fab")
			(hide yes)
			(effects
				(font
					(size 1 1)
					(thickness 0.15)
				)
				(justify mirror)
			)
		)
		(property "Dielectric" "X5R"
			(at -6.07 272.65 0)
			(layer "B.Fab")
			(hide yes)
			(effects
				(font
					(size 1 1)
					(thickness 0.15)
				)
				(justify mirror)
			)
		)
		(property "License" "Apache-2.0"
			(at -6.07 272.65 0)
			(layer "B.Fab")
			(hide yes)
			(effects
				(font
					(size 1 1)
					(thickness 0.15)
				)
				(justify mirror)
			)
		)
		(property "MPN" "GRM155R61H104KE14D"
			(at -6.07 272.65 0)
			(layer "B.Fab")
			(hide yes)
			(effects
				(font
					(size 1 1)
					(thickness 0.15)
				)
				(justify mirror)
			)
		)
		(property "Manufacturer" "Murata"
			(at -6.07 272.65 0)
			(layer "B.Fab")
			(hide yes)
			(effects
				(font
					(size 1 1)
					(thickness 0.15)
				)
				(justify mirror)
			)
		)
		(property "Public" "False"
			(at -6.07 272.65 0)
			(layer "B.Fab")
			(hide yes)
			(effects
				(font
					(size 1 1)
					(thickness 0.15)
				)
				(justify mirror)
			)
		)
		(property "Val" "100n"
			(at -6.07 272.65 0)
			(layer "B.Fab")
			(hide yes)
			(effects
				(font
					(size 1 1)
					(thickness 0.15)
				)
				(justify mirror)
			)
		)
		(property "Voltage" "50V"
			(at -6.07 272.65 0)
			(layer "B.Fab")
			(hide yes)
			(effects
				(font
					(size 1 1)
					(thickness 0.15)
				)
				(justify mirror)
			)
		)
		(sheetname "KR to SFI #2")
		(sheetfile "kr_sfi.kicad_sch")
		(attr smd)
		(fp_rect
			(start -0.925 0.47)
			(end 0.925 -0.47)
			(stroke
				(width 0.05)
				(type default)
			)
			(fill no)
			(layer "B.CrtYd")
		)
		(fp_line
			(start -0.494 0.25)
			(end -0.494 -0.248)
			(stroke
				(width 0.15)
				(type solid)
			)
			(layer "B.Fab")
		)
		(fp_line
			(start 0.504 0.25)
			(end -0.494 0.25)
			(stroke
				(width 0.15)
				(type solid)
			)
			(layer "B.Fab")
		)
		(fp_line
			(start -0.494 -0.248)
			(end 0.504 -0.248)
			(stroke
				(width 0.15)
				(type solid)
			)
			(layer "B.Fab")
		)
		(fp_line
			(start 0.504 -0.248)
			(end 0.504 0.25)
			(stroke
				(width 0.15)
				(type solid)
			)
			(layer "B.Fab")
		)
		(pad "1" smd roundrect
			(at -0.48 0 270)
			(size 0.59 0.64)
			(layers "B.Cu" "B.Mask" "B.Paste")
			(roundrect_rratio 0.25)
			(net 1 "GND")
			(pintype "passive")
			(teardrops
				(best_length_ratio 0.2)
				(max_length 1)
				(best_width_ratio 0.9)
				(max_width 2)
				(curved_edges yes)
				(filter_ratio 0.9)
				(enabled yes)
				(allow_two_segments yes)
				(prefer_zone_connections yes)
			)
		)
		(pad "2" smd roundrect
			(at 0.48 0 270)
			(size 0.59 0.64)
			(layers "B.Cu" "B.Mask" "B.Paste")
			(roundrect_rratio 0.25)
			(net 74 "+1V0")
			(pintype "passive")
			(teardrops
				(best_length_ratio 0.2)
				(max_length 1)
				(best_width_ratio 0.9)
				(max_width 2)
				(curved_edges yes)
				(filter_ratio 0.9)
				(enabled yes)
				(allow_two_segments yes)
				(prefer_zone_connections yes)
			)
		)
	)
	(footprint "antmicro-footprints:C_0402_1005Metric"
		(layer "B.Cu")
		(at 107.893 158.377 180)
		(descr "Capacitor SMD 0402")
		(tags "capacitor SMD 0402")
		(property "Reference" "C143"
			(at -3.707 0.067 0)
			(layer "B.SilkS")
			(effects
				(font
					(size 0.7 0.7)
					(thickness 0.15)
				)
				(justify left bottom mirror)
			)
		)
		(property "Value" "C_220n_0402"
			(at -1.022927 -2.155213 0)
			(layer "B.Fab")
			(effects
				(font
					(size 0.7 0.7)
					(thickness 0.15)
				)
				(justify left bottom mirror)
			)
		)
		(property "Datasheet" "https://www.yageo.com/en/Chart/Download/pdf/CC0402KRX5R6BB224"
			(at 0 0 180)
			(layer "F.Fab")
			(hide yes)
			(effects
				(font
					(size 1.27 1.27)
					(thickness 0.15)
				)
			)
		)
		(property "Author" "Antmicro"
			(at 215.786 316.754 0)
			(layer "B.Fab")
			(hide yes)
			(effects
				(font
					(size 1 1)
					(thickness 0.15)
				)
				(justify mirror)
			)
		)
		(property "Dielectric" ""
			(at 215.786 316.754 0)
			(layer "B.Fab")
			(hide yes)
			(effects
				(font
					(size 1 1)
					(thickness 0.15)
				)
				(justify mirror)
			)
		)
		(property "License" "Apache-2.0"
			(at 215.786 316.754 0)
			(layer "B.Fab")
			(hide yes)
			(effects
				(font
					(size 1 1)
					(thickness 0.15)
				)
				(justify mirror)
			)
		)
		(property "MPN" "CC0402KRX5R6BB224"
			(at 215.786 316.754 0)
			(layer "B.Fab")
			(hide yes)
			(effects
				(font
					(size 1 1)
					(thickness 0.15)
				)
				(justify mirror)
			)
		)
		(property "Manufacturer" "YAGEO"
			(at 215.786 316.754 0)
			(layer "B.Fab")
			(hide yes)
			(effects
				(font
					(size 1 1)
					(thickness 0.15)
				)
				(justify mirror)
			)
		)
		(property "Public" "False"
			(at 215.786 316.754 0)
			(layer "B.Fab")
			(hide yes)
			(effects
				(font
					(size 1 1)
					(thickness 0.15)
				)
				(justify mirror)
			)
		)
		(property "Val" "220n"
			(at 215.786 316.754 0)
			(layer "B.Fab")
			(hide yes)
			(effects
				(font
					(size 1 1)
					(thickness 0.15)
				)
				(justify mirror)
			)
		)
		(property "Voltage" ""
			(at 215.786 316.754 0)
			(layer "B.Fab")
			(hide yes)
			(effects
				(font
					(size 1 1)
					(thickness 0.15)
				)
				(justify mirror)
			)
		)
		(sheetname "PCIe redriver")
		(sheetfile "pcie_redriver.kicad_sch")
		(attr smd)
		(fp_rect
			(start -0.925 0.47)
			(end 0.925 -0.47)
			(stroke
				(width 0.05)
				(type default)
			)
			(fill no)
			(layer "B.CrtYd")
		)
		(fp_line
			(start 0.504 0.25)
			(end -0.494 0.25)
			(stroke
				(width 0.15)
				(type solid)
			)
			(layer "B.Fab")
		)
		(fp_line
			(start 0.504 -0.248)
			(end 0.504 0.25)
			(stroke
				(width 0.15)
				(type solid)
			)
			(layer "B.Fab")
		)
		(fp_line
			(start -0.494 0.25)
			(end -0.494 -0.248)
			(stroke
				(width 0.15)
				(type solid)
			)
			(layer "B.Fab")
		)
		(fp_line
			(start -0.494 -0.248)
			(end 0.504 -0.248)
			(stroke
				(width 0.15)
				(type solid)
			)
			(layer "B.Fab")
		)
		(pad "1" smd roundrect
			(at -0.48 0 180)
			(size 0.59 0.64)
			(layers "B.Cu" "B.Mask" "B.Paste")
			(roundrect_rratio 0.25)
			(net 99 "/PCIe redriver/PCIe_{O}_C.TX3-")
			(pintype "passive")
			(teardrops
				(best_length_ratio 0.2)
				(max_length 1)
				(best_width_ratio 0.9)
				(max_width 2)
				(curved_edges yes)
				(filter_ratio 0.9)
				(enabled yes)
				(allow_two_segments yes)
				(prefer_zone_connections yes)
			)
		)
		(pad "2" smd roundrect
			(at 0.48 0 180)
			(size 0.59 0.64)
			(layers "B.Cu" "B.Mask" "B.Paste")
			(roundrect_rratio 0.25)
			(net 98 "/OCuLink/PCIe_{x4}.TX3-")
			(pintype "passive")
			(teardrops
				(best_length_ratio 0.2)
				(max_length 1)
				(best_width_ratio 0.9)
				(max_width 2)
				(curved_edges yes)
				(filter_ratio 0.9)
				(enabled yes)
				(allow_two_segments yes)
				(prefer_zone_connections yes)
			)
		)
	)
)
